(kicad_sch
	(version 20250114)
	(generator "eeschema")
	(generator_version "9.0")
	(paper "A3")
	(title_block
		(title "Artix - Datacenter Secure Control Module (DC-SCM)")
		(date "2024-11-06")
		(rev "1.1.3")
	)
	(text "NVMe SSD"
		(exclude_from_sim no)
		(at 161.925 74.93 0)
		(effects
			(font
				(size 2.9972 2.9972)
				(thickness 0.5994)
				(bold yes)
			)
			(justify left bottom)
		)
	)
	(junction
		(at 254 105.41)
		(diameter 0)
		(color 0 0 0 0)
	)
	(junction
		(at 246.38 175.26)
		(diameter 0)
		(color 0 0 0 0)
	)
	(junction
		(at 191.77 82.55)
		(diameter 0)
		(color 0 0 0 0)
	)
	(junction
		(at 191.77 100.33)
		(diameter 0)
		(color 0 0 0 0)
	)
	(junction
		(at 261.62 97.79)
		(diameter 0)
		(color 0 0 0 0)
	)
	(junction
		(at 254 97.79)
		(diameter 0)
		(color 0 0 0 0)
	)
	(junction
		(at 261.62 105.41)
		(diameter 0)
		(color 0 0 0 0)
	)
	(junction
		(at 246.38 97.79)
		(diameter 0)
		(color 0 0 0 0)
	)
	(junction
		(at 269.24 105.41)
		(diameter 0)
		(color 0 0 0 0)
	)
	(junction
		(at 269.24 97.79)
		(diameter 0)
		(color 0 0 0 0)
	)
	(junction
		(at 198.12 97.79)
		(diameter 0)
		(color 0 0 0 0)
	)
	(junction
		(at 176.53 97.79)
		(diameter 0)
		(color 0 0 0 0)
	)
	(junction
		(at 198.12 82.55)
		(diameter 0)
		(color 0 0 0 0)
	)
	(no_connect
		(at 245.11 127)
	)
	(no_connect
		(at 245.11 129.54)
	)
	(no_connect
		(at 224.79 185.42)
	)
	(no_connect
		(at 245.11 110.49)
	)
	(wire
		(pts
			(xy 269.24 105.41) (xy 269.24 104.14)
		)
		(stroke
			(width 0)
			(type default)
		)
	)
	(wire
		(pts
			(xy 181.61 134.62) (xy 173.99 134.62)
		)
		(stroke
			(width 0)
			(type default)
		)
	)
	(wire
		(pts
			(xy 246.38 97.79) (xy 246.38 99.06)
		)
		(stroke
			(width 0)
			(type default)
		)
	)
	(wire
		(pts
			(xy 214.63 149.86) (xy 186.69 149.86)
		)
		(stroke
			(width 0)
			(type default)
		)
	)
	(wire
		(pts
			(xy 175.26 100.33) (xy 191.77 100.33)
		)
		(stroke
			(width 0)
			(type default)
		)
	)
	(wire
		(pts
			(xy 173.99 160.02) (xy 214.63 160.02)
		)
		(stroke
			(width 0)
			(type default)
		)
	)
	(wire
		(pts
			(xy 198.12 92.71) (xy 198.12 97.79)
		)
		(stroke
			(width 0)
			(type default)
		)
	)
	(wire
		(pts
			(xy 191.77 82.55) (xy 173.99 82.55)
		)
		(stroke
			(width 0)
			(type default)
		)
	)
	(wire
		(pts
			(xy 191.77 87.63) (xy 191.77 82.55)
		)
		(stroke
			(width 0)
			(type default)
		)
	)
	(wire
		(pts
			(xy 245.11 124.46) (xy 246.38 124.46)
		)
		(stroke
			(width 0)
			(type default)
		)
	)
	(wire
		(pts
			(xy 254 105.41) (xy 254 104.14)
		)
		(stroke
			(width 0)
			(type default)
		)
	)
	(wire
		(pts
			(xy 181.61 119.38) (xy 173.99 119.38)
		)
		(stroke
			(width 0)
			(type default)
		)
	)
	(wire
		(pts
			(xy 276.86 152.4) (xy 278.13 152.4)
		)
		(stroke
			(width 0)
			(type default)
		)
	)
	(wire
		(pts
			(xy 254 105.41) (xy 261.62 105.41)
		)
		(stroke
			(width 0)
			(type default)
		)
	)
	(wire
		(pts
			(xy 176.53 97.79) (xy 198.12 97.79)
		)
		(stroke
			(width 0)
			(type default)
		)
	)
	(wire
		(pts
			(xy 173.99 172.72) (xy 214.63 172.72)
		)
		(stroke
			(width 0)
			(type default)
		)
	)
	(wire
		(pts
			(xy 269.24 105.41) (xy 269.24 106.68)
		)
		(stroke
			(width 0)
			(type default)
		)
	)
	(wire
		(pts
			(xy 198.12 97.79) (xy 214.63 97.79)
		)
		(stroke
			(width 0)
			(type default)
		)
	)
	(wire
		(pts
			(xy 245.11 175.26) (xy 246.38 175.26)
		)
		(stroke
			(width 0)
			(type default)
		)
	)
	(wire
		(pts
			(xy 173.99 157.48) (xy 214.63 157.48)
		)
		(stroke
			(width 0)
			(type default)
		)
	)
	(wire
		(pts
			(xy 179.07 121.92) (xy 173.99 121.92)
		)
		(stroke
			(width 0)
			(type default)
		)
	)
	(wire
		(pts
			(xy 246.38 116.84) (xy 246.38 118.11)
		)
		(stroke
			(width 0)
			(type default)
		)
	)
	(wire
		(pts
			(xy 269.24 97.79) (xy 261.62 97.79)
		)
		(stroke
			(width 0)
			(type default)
		)
	)
	(wire
		(pts
			(xy 245.11 97.79) (xy 246.38 97.79)
		)
		(stroke
			(width 0)
			(type default)
		)
	)
	(wire
		(pts
			(xy 262.89 152.4) (xy 271.78 152.4)
		)
		(stroke
			(width 0)
			(type default)
		)
	)
	(wire
		(pts
			(xy 261.62 105.41) (xy 269.24 105.41)
		)
		(stroke
			(width 0)
			(type default)
		)
	)
	(wire
		(pts
			(xy 246.38 123.19) (xy 246.38 124.46)
		)
		(stroke
			(width 0)
			(type default)
		)
	)
	(wire
		(pts
			(xy 245.11 172.72) (xy 246.38 172.72)
		)
		(stroke
			(width 0)
			(type default)
		)
	)
	(wire
		(pts
			(xy 246.38 105.41) (xy 246.38 104.14)
		)
		(stroke
			(width 0)
			(type default)
		)
	)
	(wire
		(pts
			(xy 269.24 97.79) (xy 269.24 99.06)
		)
		(stroke
			(width 0)
			(type default)
		)
	)
	(wire
		(pts
			(xy 173.99 113.03) (xy 214.63 113.03)
		)
		(stroke
			(width 0)
			(type default)
		)
	)
	(wire
		(pts
			(xy 214.63 119.38) (xy 186.69 119.38)
		)
		(stroke
			(width 0)
			(type default)
		)
	)
	(wire
		(pts
			(xy 191.77 92.71) (xy 191.77 100.33)
		)
		(stroke
			(width 0)
			(type default)
		)
	)
	(wire
		(pts
			(xy 245.11 152.4) (xy 257.81 152.4)
		)
		(stroke
			(width 0)
			(type default)
		)
	)
	(wire
		(pts
			(xy 261.62 105.41) (xy 261.62 104.14)
		)
		(stroke
			(width 0)
			(type default)
		)
	)
	(wire
		(pts
			(xy 252.73 116.84) (xy 246.38 116.84)
		)
		(stroke
			(width 0)
			(type default)
		)
	)
	(wire
		(pts
			(xy 254 97.79) (xy 254 99.06)
		)
		(stroke
			(width 0)
			(type default)
		)
	)
	(wire
		(pts
			(xy 179.07 152.4) (xy 173.99 152.4)
		)
		(stroke
			(width 0)
			(type default)
		)
	)
	(wire
		(pts
			(xy 246.38 105.41) (xy 254 105.41)
		)
		(stroke
			(width 0)
			(type default)
		)
	)
	(wire
		(pts
			(xy 175.26 97.79) (xy 176.53 97.79)
		)
		(stroke
			(width 0)
			(type default)
		)
	)
	(wire
		(pts
			(xy 181.61 149.86) (xy 173.99 149.86)
		)
		(stroke
			(width 0)
			(type default)
		)
	)
	(wire
		(pts
			(xy 173.99 142.24) (xy 214.63 142.24)
		)
		(stroke
			(width 0)
			(type default)
		)
	)
	(wire
		(pts
			(xy 198.12 82.55) (xy 269.24 82.55)
		)
		(stroke
			(width 0)
			(type default)
		)
	)
	(wire
		(pts
			(xy 261.62 97.79) (xy 254 97.79)
		)
		(stroke
			(width 0)
			(type default)
		)
	)
	(wire
		(pts
			(xy 173.99 144.78) (xy 214.63 144.78)
		)
		(stroke
			(width 0)
			(type default)
		)
	)
	(wire
		(pts
			(xy 191.77 100.33) (xy 214.63 100.33)
		)
		(stroke
			(width 0)
			(type default)
		)
	)
	(wire
		(pts
			(xy 246.38 172.72) (xy 246.38 175.26)
		)
		(stroke
			(width 0)
			(type default)
		)
	)
	(wire
		(pts
			(xy 173.99 129.54) (xy 214.63 129.54)
		)
		(stroke
			(width 0)
			(type default)
		)
	)
	(wire
		(pts
			(xy 246.38 175.26) (xy 246.38 176.53)
		)
		(stroke
			(width 0)
			(type default)
		)
	)
	(wire
		(pts
			(xy 176.53 95.25) (xy 176.53 97.79)
		)
		(stroke
			(width 0)
			(type default)
		)
	)
	(wire
		(pts
			(xy 173.99 95.25) (xy 176.53 95.25)
		)
		(stroke
			(width 0)
			(type default)
		)
	)
	(wire
		(pts
			(xy 198.12 82.55) (xy 191.77 82.55)
		)
		(stroke
			(width 0)
			(type default)
		)
	)
	(wire
		(pts
			(xy 179.07 167.64) (xy 173.99 167.64)
		)
		(stroke
			(width 0)
			(type default)
		)
	)
	(wire
		(pts
			(xy 184.15 152.4) (xy 214.63 152.4)
		)
		(stroke
			(width 0)
			(type default)
		)
	)
	(wire
		(pts
			(xy 269.24 82.55) (xy 269.24 97.79)
		)
		(stroke
			(width 0)
			(type default)
		)
	)
	(wire
		(pts
			(xy 246.38 97.79) (xy 254 97.79)
		)
		(stroke
			(width 0)
			(type default)
		)
	)
	(wire
		(pts
			(xy 181.61 165.1) (xy 173.99 165.1)
		)
		(stroke
			(width 0)
			(type default)
		)
	)
	(wire
		(pts
			(xy 184.15 137.16) (xy 214.63 137.16)
		)
		(stroke
			(width 0)
			(type default)
		)
	)
	(wire
		(pts
			(xy 173.99 127) (xy 214.63 127)
		)
		(stroke
			(width 0)
			(type default)
		)
	)
	(wire
		(pts
			(xy 175.26 102.87) (xy 214.63 102.87)
		)
		(stroke
			(width 0)
			(type default)
		)
	)
	(wire
		(pts
			(xy 184.15 121.92) (xy 214.63 121.92)
		)
		(stroke
			(width 0)
			(type default)
		)
	)
	(wire
		(pts
			(xy 173.99 175.26) (xy 214.63 175.26)
		)
		(stroke
			(width 0)
			(type default)
		)
	)
	(wire
		(pts
			(xy 214.63 134.62) (xy 186.69 134.62)
		)
		(stroke
			(width 0)
			(type default)
		)
	)
	(wire
		(pts
			(xy 214.63 165.1) (xy 186.69 165.1)
		)
		(stroke
			(width 0)
			(type default)
		)
	)
	(wire
		(pts
			(xy 261.62 97.79) (xy 261.62 99.06)
		)
		(stroke
			(width 0)
			(type default)
		)
	)
	(wire
		(pts
			(xy 198.12 87.63) (xy 198.12 82.55)
		)
		(stroke
			(width 0)
			(type default)
		)
	)
	(wire
		(pts
			(xy 179.07 137.16) (xy 173.99 137.16)
		)
		(stroke
			(width 0)
			(type default)
		)
	)
	(wire
		(pts
			(xy 184.15 167.64) (xy 214.63 167.64)
		)
		(stroke
			(width 0)
			(type default)
		)
	)
	(wire
		(pts
			(xy 173.99 110.49) (xy 214.63 110.49)
		)
		(stroke
			(width 0)
			(type default)
		)
	)
	(label "NVME_LED"
		(at 256.54 152.4 180)
		(effects
			(font
				(size 1.27 1.27)
			)
			(justify right bottom)
		)
	)
	(label "PCIE_HPM_TX1_C_P"
		(at 210.82 134.62 180)
		(effects
			(font
				(size 1.27 1.27)
			)
			(justify right bottom)
		)
	)
	(label "PCIE_HPM_TX3_C_N"
		(at 212.09 167.64 180)
		(effects
			(font
				(size 1.27 1.27)
			)
			(justify right bottom)
		)
	)
	(label "PCIE_HPM_TX0_C_N"
		(at 210.82 121.92 180)
		(effects
			(font
				(size 1.27 1.27)
			)
			(justify right bottom)
		)
	)
	(label "PCIE_HPM_TX1_C_N"
		(at 210.82 137.16 180)
		(effects
			(font
				(size 1.27 1.27)
			)
			(justify right bottom)
		)
	)
	(label "PCIE_HPM_TX2_C_P"
		(at 212.09 149.86 180)
		(effects
			(font
				(size 1.27 1.27)
			)
			(justify right bottom)
		)
	)
	(label "PCIE_HPM_TX3_C_P"
		(at 212.09 165.1 180)
		(effects
			(font
				(size 1.27 1.27)
			)
			(justify right bottom)
		)
	)
	(label "PCIE_HPM_TX0_C_P"
		(at 210.82 119.38 180)
		(effects
			(font
				(size 1.27 1.27)
			)
			(justify right bottom)
		)
	)
	(label "PCIE_HPM_TX2_C_N"
		(at 212.09 152.4 180)
		(effects
			(font
				(size 1.27 1.27)
			)
			(justify right bottom)
		)
	)
	(global_label "PCIE_HPM_CLK_P"
		(shape input)
		(at 173.99 110.49 180)
		(fields_autoplaced yes)
		(effects
			(font
				(size 1.27 1.27)
			)
			(justify right)
		)
		(property "Intersheetrefs" "${INTERSHEET_REFS}"
			(at 372.745 48.26 0)
			(effects
				(font
					(size 1.27 1.27)
				)
				(justify left)
				(hide yes)
			)
		)
	)
	(global_label "PRSNT1_N"
		(shape input)
		(at 173.99 95.25 180)
		(fields_autoplaced yes)
		(effects
			(font
				(size 1.27 1.27)
			)
			(justify right)
		)
		(property "Intersheetrefs" "${INTERSHEET_REFS}"
			(at 80.645 165.1 0)
			(effects
				(font
					(size 1.27 1.27)
				)
				(justify right)
				(hide yes)
			)
		)
	)
	(global_label "PCIE_HPM_RX[2]_P"
		(shape input)
		(at 173.99 157.48 180)
		(fields_autoplaced yes)
		(effects
			(font
				(size 1.27 1.27)
			)
			(justify right)
		)
		(property "Intersheetrefs" "${INTERSHEET_REFS}"
			(at 372.745 49.53 0)
			(effects
				(font
					(size 1.27 1.27)
				)
				(justify left)
				(hide yes)
			)
		)
	)
	(global_label "PCIE_HPM_TX[1]_P"
		(shape input)
		(at 173.99 134.62 180)
		(fields_autoplaced yes)
		(effects
			(font
				(size 1.27 1.27)
			)
			(justify right)
		)
		(property "Intersheetrefs" "${INTERSHEET_REFS}"
			(at 372.745 49.53 0)
			(effects
				(font
					(size 1.27 1.27)
				)
				(justify left)
				(hide yes)
			)
		)
	)
	(global_label "PCIE_HPM_RX[0]_N"
		(shape input)
		(at 173.99 129.54 180)
		(fields_autoplaced yes)
		(effects
			(font
				(size 1.27 1.27)
			)
			(justify right)
		)
		(property "Intersheetrefs" "${INTERSHEET_REFS}"
			(at 372.745 49.53 0)
			(effects
				(font
					(size 1.27 1.27)
				)
				(justify left)
				(hide yes)
			)
		)
	)
	(global_label "PCIE_HPM_TX[3]_N"
		(shape input)
		(at 173.99 167.64 180)
		(fields_autoplaced yes)
		(effects
			(font
				(size 1.27 1.27)
			)
			(justify right)
		)
		(property "Intersheetrefs" "${INTERSHEET_REFS}"
			(at 372.745 49.53 0)
			(effects
				(font
					(size 1.27 1.27)
				)
				(justify left)
				(hide yes)
			)
		)
	)
	(global_label "PCIE_HPM_TX[3]_P"
		(shape input)
		(at 173.99 165.1 180)
		(fields_autoplaced yes)
		(effects
			(font
				(size 1.27 1.27)
			)
			(justify right)
		)
		(property "Intersheetrefs" "${INTERSHEET_REFS}"
			(at 372.745 49.53 0)
			(effects
				(font
					(size 1.27 1.27)
				)
				(justify left)
				(hide yes)
			)
		)
	)
	(global_label "PCIE_HPM_TX[2]_P"
		(shape input)
		(at 173.99 149.86 180)
		(fields_autoplaced yes)
		(effects
			(font
				(size 1.27 1.27)
			)
			(justify right)
		)
		(property "Intersheetrefs" "${INTERSHEET_REFS}"
			(at 372.745 49.53 0)
			(effects
				(font
					(size 1.27 1.27)
				)
				(justify left)
				(hide yes)
			)
		)
	)
	(global_label "VCC3V3"
		(shape input)
		(at 173.99 82.55 180)
		(fields_autoplaced yes)
		(effects
			(font
				(size 1.27 1.27)
			)
			(justify right)
		)
		(property "Intersheetrefs" "${INTERSHEET_REFS}"
			(at 135.89 177.8 0)
			(effects
				(font
					(size 1.27 1.27)
				)
				(hide yes)
			)
		)
	)
	(global_label "PCIE_HPM_TX[0]_P"
		(shape input)
		(at 173.99 119.38 180)
		(fields_autoplaced yes)
		(effects
			(font
				(size 1.27 1.27)
			)
			(justify right)
		)
		(property "Intersheetrefs" "${INTERSHEET_REFS}"
			(at 372.745 49.53 0)
			(effects
				(font
					(size 1.27 1.27)
				)
				(justify left)
				(hide yes)
			)
		)
	)
	(global_label "PCIE_HPM_TX[2]_N"
		(shape input)
		(at 173.99 152.4 180)
		(fields_autoplaced yes)
		(effects
			(font
				(size 1.27 1.27)
			)
			(justify right)
		)
		(property "Intersheetrefs" "${INTERSHEET_REFS}"
			(at 372.745 49.53 0)
			(effects
				(font
					(size 1.27 1.27)
				)
				(justify left)
				(hide yes)
			)
		)
	)
	(global_label "PCIE_HPM_CLK_N"
		(shape input)
		(at 173.99 113.03 180)
		(fields_autoplaced yes)
		(effects
			(font
				(size 1.27 1.27)
			)
			(justify right)
		)
		(property "Intersheetrefs" "${INTERSHEET_REFS}"
			(at 372.745 48.26 0)
			(effects
				(font
					(size 1.27 1.27)
				)
				(justify left)
				(hide yes)
			)
		)
	)
	(global_label "PCIE_HPM_RX[3]_P"
		(shape input)
		(at 173.99 172.72 180)
		(fields_autoplaced yes)
		(effects
			(font
				(size 1.27 1.27)
			)
			(justify right)
		)
		(property "Intersheetrefs" "${INTERSHEET_REFS}"
			(at 372.745 49.53 0)
			(effects
				(font
					(size 1.27 1.27)
				)
				(justify left)
				(hide yes)
			)
		)
	)
	(global_label "VCC1V8"
		(shape input)
		(at 252.73 116.84 0)
		(fields_autoplaced yes)
		(effects
			(font
				(size 1.27 1.27)
			)
			(justify left)
		)
		(property "Intersheetrefs" "${INTERSHEET_REFS}"
			(at 290.83 8.255 0)
			(effects
				(font
					(size 1.27 1.27)
				)
				(hide yes)
			)
		)
	)
	(global_label "PCIE_HPM_TX[0]_N"
		(shape input)
		(at 173.99 121.92 180)
		(fields_autoplaced yes)
		(effects
			(font
				(size 1.27 1.27)
			)
			(justify right)
		)
		(property "Intersheetrefs" "${INTERSHEET_REFS}"
			(at 372.745 49.53 0)
			(effects
				(font
					(size 1.27 1.27)
				)
				(justify left)
				(hide yes)
			)
		)
	)
	(global_label "PCIE_HPM_RX[2]_N"
		(shape input)
		(at 173.99 160.02 180)
		(fields_autoplaced yes)
		(effects
			(font
				(size 1.27 1.27)
			)
			(justify right)
		)
		(property "Intersheetrefs" "${INTERSHEET_REFS}"
			(at 372.745 49.53 0)
			(effects
				(font
					(size 1.27 1.27)
				)
				(justify left)
				(hide yes)
			)
		)
	)
	(global_label "PCIE_HPM_RX[1]_P"
		(shape input)
		(at 173.99 142.24 180)
		(fields_autoplaced yes)
		(effects
			(font
				(size 1.27 1.27)
			)
			(justify right)
		)
		(property "Intersheetrefs" "${INTERSHEET_REFS}"
			(at 372.745 49.53 0)
			(effects
				(font
					(size 1.27 1.27)
				)
				(justify left)
				(hide yes)
			)
		)
	)
	(global_label "VCC3V3"
		(shape input)
		(at 278.13 152.4 0)
		(fields_autoplaced yes)
		(effects
			(font
				(size 1.27 1.27)
			)
			(justify left)
		)
		(property "Intersheetrefs" "${INTERSHEET_REFS}"
			(at 381.635 240.03 90)
			(effects
				(font
					(size 1.27 1.27)
				)
				(justify right)
				(hide yes)
			)
		)
	)
	(global_label "PCIE_HPM_TX[1]_N"
		(shape input)
		(at 173.99 137.16 180)
		(fields_autoplaced yes)
		(effects
			(font
				(size 1.27 1.27)
			)
			(justify right)
		)
		(property "Intersheetrefs" "${INTERSHEET_REFS}"
			(at 372.745 49.53 0)
			(effects
				(font
					(size 1.27 1.27)
				)
				(justify left)
				(hide yes)
			)
		)
	)
	(global_label "PCIE_HPM_RX[1]_N"
		(shape input)
		(at 173.99 144.78 180)
		(fields_autoplaced yes)
		(effects
			(font
				(size 1.27 1.27)
			)
			(justify right)
		)
		(property "Intersheetrefs" "${INTERSHEET_REFS}"
			(at 372.745 49.53 0)
			(effects
				(font
					(size 1.27 1.27)
				)
				(justify left)
				(hide yes)
			)
		)
	)
	(global_label "PCIE_HPM_RX[0]_P"
		(shape input)
		(at 173.99 127 180)
		(fields_autoplaced yes)
		(effects
			(font
				(size 1.27 1.27)
			)
			(justify right)
		)
		(property "Intersheetrefs" "${INTERSHEET_REFS}"
			(at 372.745 49.53 0)
			(effects
				(font
					(size 1.27 1.27)
				)
				(justify left)
				(hide yes)
			)
		)
	)
	(global_label "PCIE_HPM_RX[3]_N"
		(shape input)
		(at 173.99 175.26 180)
		(fields_autoplaced yes)
		(effects
			(font
				(size 1.27 1.27)
			)
			(justify right)
		)
		(property "Intersheetrefs" "${INTERSHEET_REFS}"
			(at 372.745 49.53 0)
			(effects
				(font
					(size 1.27 1.27)
				)
				(justify left)
				(hide yes)
			)
		)
	)
	(symbol
		(lib_id "antmicroCapacitorsmisc:C_100n_6V3_0402")
		(at 186.69 119.38 180)
		(unit 1)
		(exclude_from_sim no)
		(in_bom yes)
		(on_board yes)
		(dnp no)
		(property "Reference" "C27"
			(at 179.07 118.11 0)
			(effects
				(font
					(size 1.27 1.27)
				)
			)
		)
		(property "Value" "C_100n_6V3_0402"
			(at 166.37 109.22 0)
			(effects
				(font
					(size 1.27 1.27)
					(thickness 0.15)
				)
				(justify left bottom)
				(hide yes)
			)
		)
		(property "Footprint" "antmicro-footprints:C_0402_1005Metric"
			(at 166.37 106.68 0)
			(effects
				(font
					(size 1.27 1.27)
					(thickness 0.15)
				)
				(justify left bottom)
				(hide yes)
			)
		)
		(property "Datasheet" "https://www.passivecomponent.com/wp-content/uploads/datasheet/WTC_MLCC_General_Purpose.pdf"
			(at 166.37 104.14 0)
			(effects
				(font
					(size 1.27 1.27)
					(thickness 0.15)
				)
				(justify left bottom)
				(hide yes)
			)
		)
		(property "Description" "SMT Multilayer Ceramic Capacitor, 0.1 µF, 6.3 V, 0402 [1005 Metric], ± 10%, X5R, Walsin MLCC"
			(at 186.69 119.38 0)
			(effects
				(font
					(size 1.27 1.27)
				)
				(hide yes)
			)
		)
		(property "Manufacturer" "Walsin"
			(at 166.37 99.06 0)
			(effects
				(font
					(size 1.27 1.27)
					(thickness 0.15)
				)
				(justify left bottom)
				(hide yes)
			)
		)
		(property "MPN" "0402X104K6R3CT"
			(at 166.37 101.6 0)
			(effects
				(font
					(size 1.27 1.27)
					(thickness 0.15)
				)
				(justify left bottom)
				(hide yes)
			)
		)
		(property "Val" "100n"
			(at 188.595 118.11 0)
			(effects
				(font
					(size 1.27 1.27)
					(thickness 0.15)
				)
			)
		)
		(property "License" "Apache-2.0"
			(at 166.37 96.52 0)
			(effects
				(font
					(size 1.27 1.27)
					(thickness 0.15)
				)
				(justify left bottom)
				(hide yes)
			)
		)
		(property "Author" "Antmicro"
			(at 166.37 93.98 0)
			(effects
				(font
					(size 1.27 1.27)
					(thickness 0.15)
				)
				(justify left bottom)
				(hide yes)
			)
		)
		(property "Voltage" ""
			(at 166.37 91.44 0)
			(effects
				(font
					(size 1.27 1.27)
				)
				(justify left bottom)
				(hide yes)
			)
		)
		(property "Dielectric" ""
			(at 166.37 88.9 0)
			(effects
				(font
					(size 1.27 1.27)
				)
				(justify left bottom)
				(hide yes)
			)
		)
		(property "Public" "False"
			(at 166.37 86.36 0)
			(effects
				(font
					(size 1.27 1.27)
				)
				(justify left bottom)
				(hide yes)
			)
		)
		(pin "1"
		)
		(pin "2"
		)
		(instances
			(project "artix-dc-scm"
				(path ""
					(reference "C27")
					(unit 1)
				)
			)
		)
	)
	(symbol
		(lib_id "antmicroCapacitorsmisc:C_100n_6V3_0402")
		(at 184.15 121.92 180)
		(unit 1)
		(exclude_from_sim no)
		(in_bom yes)
		(on_board yes)
		(dnp no)
		(property "Reference" "C29"
			(at 178.435 120.65 0)
			(effects
				(font
					(size 1.27 1.27)
				)
			)
		)
		(property "Value" "C_100n_6V3_0402"
			(at 163.83 111.76 0)
			(effects
				(font
					(size 1.27 1.27)
					(thickness 0.15)
				)
				(justify left bottom)
				(hide yes)
			)
		)
		(property "Footprint" "antmicro-footprints:C_0402_1005Metric"
			(at 163.83 109.22 0)
			(effects
				(font
					(size 1.27 1.27)
					(thickness 0.15)
				)
				(justify left bottom)
				(hide yes)
			)
		)
		(property "Datasheet" "https://www.passivecomponent.com/wp-content/uploads/datasheet/WTC_MLCC_General_Purpose.pdf"
			(at 163.83 106.68 0)
			(effects
				(font
					(size 1.27 1.27)
					(thickness 0.15)
				)
				(justify left bottom)
				(hide yes)
			)
		)
		(property "Description" "SMT Multilayer Ceramic Capacitor, 0.1 µF, 6.3 V, 0402 [1005 Metric], ± 10%, X5R, Walsin MLCC"
			(at 184.15 121.92 0)
			(effects
				(font
					(size 1.27 1.27)
				)
				(hide yes)
			)
		)
		(property "Manufacturer" "Walsin"
			(at 163.83 101.6 0)
			(effects
				(font
					(size 1.27 1.27)
					(thickness 0.15)
				)
				(justify left bottom)
				(hide yes)
			)
		)
		(property "MPN" "0402X104K6R3CT"
			(at 163.83 104.14 0)
			(effects
				(font
					(size 1.27 1.27)
					(thickness 0.15)
				)
				(justify left bottom)
				(hide yes)
			)
		)
		(property "Val" "100n"
			(at 187.96 120.65 0)
			(effects
				(font
					(size 1.27 1.27)
					(thickness 0.15)
				)
			)
		)
		(property "License" "Apache-2.0"
			(at 163.83 99.06 0)
			(effects
				(font
					(size 1.27 1.27)
					(thickness 0.15)
				)
				(justify left bottom)
				(hide yes)
			)
		)
		(property "Author" "Antmicro"
			(at 163.83 96.52 0)
			(effects
				(font
					(size 1.27 1.27)
					(thickness 0.15)
				)
				(justify left bottom)
				(hide yes)
			)
		)
		(property "Voltage" ""
			(at 163.83 93.98 0)
			(effects
				(font
					(size 1.27 1.27)
				)
				(justify left bottom)
				(hide yes)
			)
		)
		(property "Dielectric" ""
			(at 163.83 91.44 0)
			(effects
				(font
					(size 1.27 1.27)
				)
				(justify left bottom)
				(hide yes)
			)
		)
		(property "Public" "False"
			(at 163.83 88.9 0)
			(effects
				(font
					(size 1.27 1.27)
				)
				(justify left bottom)
				(hide yes)
			)
		)
		(pin "1"
		)
		(pin "2"
		)
		(instances
			(project "artix-dc-scm"
				(path ""
					(reference "C29")
					(unit 1)
				)
			)
		)
	)
	(symbol
		(lib_id "antmicroCapacitorsmisc:C_100n_6V3_0402")
		(at 186.69 134.62 180)
		(unit 1)
		(exclude_from_sim no)
		(in_bom yes)
		(on_board yes)
		(dnp no)
		(property "Reference" "C28"
			(at 178.435 133.35 0)
			(effects
				(font
					(size 1.27 1.27)
				)
			)
		)
		(property "Value" "C_100n_6V3_0402"
			(at 166.37 124.46 0)
			(effects
				(font
					(size 1.27 1.27)
					(thickness 0.15)
				)
				(justify left bottom)
				(hide yes)
			)
		)
		(property "Footprint" "antmicro-footprints:C_0402_1005Metric"
			(at 166.37 121.92 0)
			(effects
				(font
					(size 1.27 1.27)
					(thickness 0.15)
				)
				(justify left bottom)
				(hide yes)
			)
		)
		(property "Datasheet" "https://www.passivecomponent.com/wp-content/uploads/datasheet/WTC_MLCC_General_Purpose.pdf"
			(at 166.37 119.38 0)
			(effects
				(font
					(size 1.27 1.27)
					(thickness 0.15)
				)
				(justify left bottom)
				(hide yes)
			)
		)
		(property "Description" "SMT Multilayer Ceramic Capacitor, 0.1 µF, 6.3 V, 0402 [1005 Metric], ± 10%, X5R, Walsin MLCC"
			(at 186.69 134.62 0)
			(effects
				(font
					(size 1.27 1.27)
				)
				(hide yes)
			)
		)
		(property "Manufacturer" "Walsin"
			(at 166.37 114.3 0)
			(effects
				(font
					(size 1.27 1.27)
					(thickness 0.15)
				)
				(justify left bottom)
				(hide yes)
			)
		)
		(property "MPN" "0402X104K6R3CT"
			(at 166.37 116.84 0)
			(effects
				(font
					(size 1.27 1.27)
					(thickness 0.15)
				)
				(justify left bottom)
				(hide yes)
			)
		)
		(property "Val" "100n"
			(at 188.595 133.35 0)
			(effects
				(font
					(size 1.27 1.27)
					(thickness 0.15)
				)
			)
		)
		(property "License" "Apache-2.0"
			(at 166.37 111.76 0)
			(effects
				(font
					(size 1.27 1.27)
					(thickness 0.15)
				)
				(justify left bottom)
				(hide yes)
			)
		)
		(property "Author" "Antmicro"
			(at 166.37 109.22 0)
			(effects
				(font
					(size 1.27 1.27)
					(thickness 0.15)
				)
				(justify left bottom)
				(hide yes)
			)
		)
		(property "Voltage" ""
			(at 166.37 106.68 0)
			(effects
				(font
					(size 1.27 1.27)
				)
				(justify left bottom)
				(hide yes)
			)
		)
		(property "Dielectric" ""
			(at 166.37 104.14 0)
			(effects
				(font
					(size 1.27 1.27)
				)
				(justify left bottom)
				(hide yes)
			)
		)
		(property "Public" "False"
			(at 166.37 101.6 0)
			(effects
				(font
					(size 1.27 1.27)
				)
				(justify left bottom)
				(hide yes)
			)
		)
		(pin "1"
		)
		(pin "2"
		)
		(instances
			(project "artix-dc-scm"
				(path ""
					(reference "C28")
					(unit 1)
				)
			)
		)
	)
	(symbol
		(lib_id "antmicroCapacitorsmisc:C_100n_6V3_0402")
		(at 184.15 137.16 180)
		(unit 1)
		(exclude_from_sim no)
		(in_bom yes)
		(on_board yes)
		(dnp no)
		(property "Reference" "C30"
			(at 177.8 135.89 0)
			(effects
				(font
					(size 1.27 1.27)
				)
			)
		)
		(property "Value" "C_100n_6V3_0402"
			(at 163.83 127 0)
			(effects
				(font
					(size 1.27 1.27)
					(thickness 0.15)
				)
				(justify left bottom)
				(hide yes)
			)
		)
		(property "Footprint" "antmicro-footprints:C_0402_1005Metric"
			(at 163.83 124.46 0)
			(effects
				(font
					(size 1.27 1.27)
					(thickness 0.15)
				)
				(justify left bottom)
				(hide yes)
			)
		)
		(property "Datasheet" "https://www.passivecomponent.com/wp-content/uploads/datasheet/WTC_MLCC_General_Purpose.pdf"
			(at 163.83 121.92 0)
			(effects
				(font
					(size 1.27 1.27)
					(thickness 0.15)
				)
				(justify left bottom)
				(hide yes)
			)
		)
		(property "Description" "SMT Multilayer Ceramic Capacitor, 0.1 µF, 6.3 V, 0402 [1005 Metric], ± 10%, X5R, Walsin MLCC"
			(at 184.15 137.16 0)
			(effects
				(font
					(size 1.27 1.27)
				)
				(hide yes)
			)
		)
		(property "Manufacturer" "Walsin"
			(at 163.83 116.84 0)
			(effects
				(font
					(size 1.27 1.27)
					(thickness 0.15)
				)
				(justify left bottom)
				(hide yes)
			)
		)
		(property "MPN" "0402X104K6R3CT"
			(at 163.83 119.38 0)
			(effects
				(font
					(size 1.27 1.27)
					(thickness 0.15)
				)
				(justify left bottom)
				(hide yes)
			)
		)
		(property "Val" "100n"
			(at 187.96 135.89 0)
			(effects
				(font
					(size 1.27 1.27)
					(thickness 0.15)
				)
			)
		)
		(property "License" "Apache-2.0"
			(at 163.83 114.3 0)
			(effects
				(font
					(size 1.27 1.27)
					(thickness 0.15)
				)
				(justify left bottom)
				(hide yes)
			)
		)
		(property "Author" "Antmicro"
			(at 163.83 111.76 0)
			(effects
				(font
					(size 1.27 1.27)
					(thickness 0.15)
				)
				(justify left bottom)
				(hide yes)
			)
		)
		(property "Voltage" ""
			(at 163.83 109.22 0)
			(effects
				(font
					(size 1.27 1.27)
				)
				(justify left bottom)
				(hide yes)
			)
		)
		(property "Dielectric" ""
			(at 163.83 106.68 0)
			(effects
				(font
					(size 1.27 1.27)
				)
				(justify left bottom)
				(hide yes)
			)
		)
		(property "Public" "False"
			(at 163.83 104.14 0)
			(effects
				(font
					(size 1.27 1.27)
				)
				(justify left bottom)
				(hide yes)
			)
		)
		(pin "1"
		)
		(pin "2"
		)
		(instances
			(project "artix-dc-scm"
				(path ""
					(reference "C30")
					(unit 1)
				)
			)
		)
	)
	(symbol
		(lib_id "antmicroPciConnectors:Bus_M.2_1-2199230-6")
		(at 214.63 97.79 0)
		(unit 1)
		(exclude_from_sim no)
		(in_bom yes)
		(on_board yes)
		(dnp no)
		(fields_autoplaced yes)
		(property "Reference" "J2"
			(at 229.87 89.535 0)
			(effects
				(font
					(size 1.27 1.27)
				)
			)
		)
		(property "Value" "Bus_M.2_1-2199230-6"
			(at 229.87 92.075 0)
			(effects
				(font
					(size 1.27 1.27)
					(thickness 0.15)
				)
				(hide yes)
			)
		)
		(property "Footprint" "antmicro-footprints:Bus_M.2_Socket_Key_M_TE_1-2199230-6"
			(at 260.35 102.87 0)
			(effects
				(font
					(size 1.27 1.27)
					(thickness 0.15)
				)
				(justify left bottom)
				(hide yes)
			)
		)
		(property "Datasheet" "https://www.te.com/commerce/DocumentDelivery/DDEController?Action=srchrtrv&DocNm=2199230&DocType=Customer+Drawing&DocLang=English"
			(at 260.35 105.41 0)
			(effects
				(font
					(size 1.27 1.27)
					(thickness 0.15)
				)
				(justify left bottom)
				(hide yes)
			)
		)
		(property "Description" "Key M Card Edge Connector, 0, Dual Side, 67 Contacts, Surface Mount, Right Angle, Solder"
			(at 214.63 97.79 0)
			(effects
				(font
					(size 1.27 1.27)
				)
				(hide yes)
			)
		)
		(property "Manufacturer" "TE Connectivity"
			(at 260.35 107.95 0)
			(effects
				(font
					(size 1.27 1.27)
					(thickness 0.15)
				)
				(justify left bottom)
				(hide yes)
			)
		)
		(property "MPN" "1-2199230-6"
			(at 229.87 92.075 0)
			(effects
				(font
					(size 1.27 1.27)
					(thickness 0.15)
				)
			)
		)
		(property "Author" "Antmicro"
			(at 260.35 113.03 0)
			(effects
				(font
					(size 1.27 1.27)
					(thickness 0.15)
				)
				(justify left bottom)
				(hide yes)
			)
		)
		(property "License" "Apache-2.0"
			(at 260.35 115.57 0)
			(effects
				(font
					(size 1.27 1.27)
					(thickness 0.15)
				)
				(justify left bottom)
				(hide yes)
			)
		)
		(property "VSD_Class" "M.2 Key M"
			(at 260.35 120.65 0)
			(effects
				(font
					(size 1.27 1.27)
				)
				(justify left bottom)
				(hide yes)
			)
		)
		(pin "1"
		)
		(pin "10"
		)
		(pin "11"
		)
		(pin "12"
		)
		(pin "13"
		)
		(pin "14"
		)
		(pin "15"
		)
		(pin "16"
		)
		(pin "17"
		)
		(pin "18"
		)
		(pin "19"
		)
		(pin "2"
		)
		(pin "20"
		)
		(pin "21"
		)
		(pin "22"
		)
		(pin "23"
		)
		(pin "24"
		)
		(pin "25"
		)
		(pin "26"
		)
		(pin "27"
		)
		(pin "28"
		)
		(pin "29"
		)
		(pin "3"
		)
		(pin "30"
		)
		(pin "31"
		)
		(pin "32"
		)
		(pin "33"
		)
		(pin "34"
		)
		(pin "35"
		)
		(pin "36"
		)
		(pin "37"
		)
		(pin "38"
		)
		(pin "39"
		)
		(pin "4"
		)
		(pin "40"
		)
		(pin "41"
		)
		(pin "42"
		)
		(pin "43"
		)
		(pin "44"
		)
		(pin "45"
		)
		(pin "46"
		)
		(pin "47"
		)
		(pin "48"
		)
		(pin "49"
		)
		(pin "5"
		)
		(pin "50"
		)
		(pin "51"
		)
		(pin "52"
		)
		(pin "53"
		)
		(pin "54"
		)
		(pin "55"
		)
		(pin "56"
		)
		(pin "57"
		)
		(pin "58"
		)
		(pin "6"
		)
		(pin "67"
		)
		(pin "68"
		)
		(pin "69"
		)
		(pin "7"
		)
		(pin "70"
		)
		(pin "71"
		)
		(pin "72"
		)
		(pin "73"
		)
		(pin "74"
		)
		(pin "75"
		)
		(pin "8"
		)
		(pin "9"
		)
		(pin "MP1"
		)
		(pin "MP2"
		)
		(instances
			(project "artix-dc-scm"
				(path ""
					(reference "J2")
					(unit 1)
				)
			)
		)
	)
	(symbol
		(lib_id "antmicroResistors0402:R_10k_0402")
		(at 191.77 87.63 270)
		(unit 1)
		(exclude_from_sim no)
		(in_bom yes)
		(on_board yes)
		(dnp no)
		(property "Reference" "R17"
			(at 193.04 88.9 90)
			(effects
				(font
					(size 1.27 1.27)
				)
				(justify left)
			)
		)
		(property "Value" "R_10k_0402"
			(at 179.07 107.95 0)
			(effects
				(font
					(size 1.27 1.27)
					(thickness 0.15)
				)
				(justify left bottom)
				(hide yes)
			)
		)
		(property "Footprint" "antmicro-footprints:R_0402_1005Metric"
			(at 176.53 107.95 0)
			(effects
				(font
					(size 1.27 1.27)
					(thickness 0.15)
				)
				(justify left bottom)
				(hide yes)
			)
		)
		(property "Datasheet" "https://www.bourns.com/docs/product-datasheets/cr.pdf"
			(at 173.99 107.95 0)
			(effects
				(font
					(size 1.27 1.27)
					(thickness 0.15)
				)
				(justify left bottom)
				(hide yes)
			)
		)
		(property "Description" "SMD Chip Resistor, 10 kohm, ± 1%, 62.5 mW, 0402 [1005 Metric], Thick Film, General Purpose"
			(at 191.77 87.63 0)
			(effects
				(font
					(size 1.27 1.27)
				)
				(hide yes)
			)
		)
		(property "Manufacturer" "Bourns"
			(at 168.91 107.95 0)
			(effects
				(font
					(size 1.27 1.27)
					(thickness 0.15)
				)
				(justify left bottom)
				(hide yes)
			)
		)
		(property "MPN" "CR0402-FX-1002GLF"
			(at 171.45 107.95 0)
			(effects
				(font
					(size 1.27 1.27)
					(thickness 0.15)
				)
				(justify left bottom)
				(hide yes)
			)
		)
		(property "Val" "10k"
			(at 193.04 91.44 90)
			(effects
				(font
					(size 1.27 1.27)
					(thickness 0.15)
				)
				(justify left)
			)
		)
		(property "License" "Apache-2.0"
			(at 166.37 107.95 0)
			(effects
				(font
					(size 1.27 1.27)
					(thickness 0.15)
				)
				(justify left bottom)
				(hide yes)
			)
		)
		(property "Author" "Antmicro"
			(at 163.83 107.95 0)
			(effects
				(font
					(size 1.27 1.27)
					(thickness 0.15)
				)
				(justify left bottom)
				(hide yes)
			)
		)
		(property "Tolerance" "1%"
			(at 181.61 107.95 0)
			(effects
				(font
					(size 1.27 1.27)
				)
				(justify left bottom)
				(hide yes)
			)
		)
		(pin "1"
		)
		(pin "2"
		)
		(instances
			(project "artix-dc-scm"
				(path ""
					(reference "R17")
					(unit 1)
				)
			)
		)
	)
	(symbol
		(lib_id "antmicroResistors0402:R_10k_0402")
		(at 198.12 87.63 270)
		(unit 1)
		(exclude_from_sim no)
		(in_bom yes)
		(on_board yes)
		(dnp no)
		(property "Reference" "R19"
			(at 199.39 88.9 90)
			(effects
				(font
					(size 1.27 1.27)
				)
				(justify left)
			)
		)
		(property "Value" "R_10k_0402"
			(at 185.42 107.95 0)
			(effects
				(font
					(size 1.27 1.27)
					(thickness 0.15)
				)
				(justify left bottom)
				(hide yes)
			)
		)
		(property "Footprint" "antmicro-footprints:R_0402_1005Metric"
			(at 182.88 107.95 0)
			(effects
				(font
					(size 1.27 1.27)
					(thickness 0.15)
				)
				(justify left bottom)
				(hide yes)
			)
		)
		(property "Datasheet" "https://www.bourns.com/docs/product-datasheets/cr.pdf"
			(at 180.34 107.95 0)
			(effects
				(font
					(size 1.27 1.27)
					(thickness 0.15)
				)
				(justify left bottom)
				(hide yes)
			)
		)
		(property "Description" "SMD Chip Resistor, 10 kohm, ± 1%, 62.5 mW, 0402 [1005 Metric], Thick Film, General Purpose"
			(at 198.12 87.63 0)
			(effects
				(font
					(size 1.27 1.27)
				)
				(hide yes)
			)
		)
		(property "Manufacturer" "Bourns"
			(at 175.26 107.95 0)
			(effects
				(font
					(size 1.27 1.27)
					(thickness 0.15)
				)
				(justify left bottom)
				(hide yes)
			)
		)
		(property "MPN" "CR0402-FX-1002GLF"
			(at 177.8 107.95 0)
			(effects
				(font
					(size 1.27 1.27)
					(thickness 0.15)
				)
				(justify left bottom)
				(hide yes)
			)
		)
		(property "Val" "10k"
			(at 199.39 91.44 90)
			(effects
				(font
					(size 1.27 1.27)
					(thickness 0.15)
				)
				(justify left)
			)
		)
		(property "License" "Apache-2.0"
			(at 172.72 107.95 0)
			(effects
				(font
					(size 1.27 1.27)
					(thickness 0.15)
				)
				(justify left bottom)
				(hide yes)
			)
		)
		(property "Author" "Antmicro"
			(at 170.18 107.95 0)
			(effects
				(font
					(size 1.27 1.27)
					(thickness 0.15)
				)
				(justify left bottom)
				(hide yes)
			)
		)
		(property "Tolerance" "1%"
			(at 187.96 107.95 0)
			(effects
				(font
					(size 1.27 1.27)
				)
				(justify left bottom)
				(hide yes)
			)
		)
		(pin "1"
		)
		(pin "2"
		)
		(instances
			(project "artix-dc-scm"
				(path ""
					(reference "R19")
					(unit 1)
				)
			)
		)
	)
	(symbol
		(lib_id "antmicroResistors0402:R_10k_0402")
		(at 246.38 118.11 270)
		(unit 1)
		(exclude_from_sim no)
		(in_bom yes)
		(on_board yes)
		(dnp no)
		(property "Reference" "R20"
			(at 247.65 119.38 90)
			(effects
				(font
					(size 1.27 1.27)
				)
				(justify left)
			)
		)
		(property "Value" "R_10k_0402"
			(at 233.68 138.43 0)
			(effects
				(font
					(size 1.27 1.27)
					(thickness 0.15)
				)
				(justify left bottom)
				(hide yes)
			)
		)
		(property "Footprint" "antmicro-footprints:R_0402_1005Metric"
			(at 231.14 138.43 0)
			(effects
				(font
					(size 1.27 1.27)
					(thickness 0.15)
				)
				(justify left bottom)
				(hide yes)
			)
		)
		(property "Datasheet" "https://www.bourns.com/docs/product-datasheets/cr.pdf"
			(at 228.6 138.43 0)
			(effects
				(font
					(size 1.27 1.27)
					(thickness 0.15)
				)
				(justify left bottom)
				(hide yes)
			)
		)
		(property "Description" "SMD Chip Resistor, 10 kohm, ± 1%, 62.5 mW, 0402 [1005 Metric], Thick Film, General Purpose"
			(at 246.38 118.11 0)
			(effects
				(font
					(size 1.27 1.27)
				)
				(hide yes)
			)
		)
		(property "Manufacturer" "Bourns"
			(at 223.52 138.43 0)
			(effects
				(font
					(size 1.27 1.27)
					(thickness 0.15)
				)
				(justify left bottom)
				(hide yes)
			)
		)
		(property "MPN" "CR0402-FX-1002GLF"
			(at 226.06 138.43 0)
			(effects
				(font
					(size 1.27 1.27)
					(thickness 0.15)
				)
				(justify left bottom)
				(hide yes)
			)
		)
		(property "Val" "10k"
			(at 247.65 121.92 90)
			(effects
				(font
					(size 1.27 1.27)
					(thickness 0.15)
				)
				(justify left)
			)
		)
		(property "License" "Apache-2.0"
			(at 220.98 138.43 0)
			(effects
				(font
					(size 1.27 1.27)
					(thickness 0.15)
				)
				(justify left bottom)
				(hide yes)
			)
		)
		(property "Author" "Antmicro"
			(at 218.44 138.43 0)
			(effects
				(font
					(size 1.27 1.27)
					(thickness 0.15)
				)
				(justify left bottom)
				(hide yes)
			)
		)
		(property "Tolerance" "1%"
			(at 236.22 138.43 0)
			(effects
				(font
					(size 1.27 1.27)
				)
				(justify left bottom)
				(hide yes)
			)
		)
		(pin "1"
		)
		(pin "2"
		)
		(instances
			(project "artix-dc-scm"
				(path ""
					(reference "R20")
					(unit 1)
				)
			)
		)
	)
	(symbol
		(lib_id "antmicroResistors0402:R_330R_0402")
		(at 271.78 152.4 0)
		(mirror x)
		(unit 1)
		(exclude_from_sim no)
		(in_bom yes)
		(on_board yes)
		(dnp no)
		(property "Reference" "R18"
			(at 274.32 149.86 0)
			(effects
				(font
					(size 1.27 1.27)
				)
			)
		)
		(property "Value" "R_330R_0402"
			(at 292.1 139.7 0)
			(effects
				(font
					(size 1.27 1.27)
					(thickness 0.15)
				)
				(justify left bottom)
				(hide yes)
			)
		)
		(property "Footprint" "antmicro-footprints:R_0402_1005Metric"
			(at 292.1 137.16 0)
			(effects
				(font
					(size 1.27 1.27)
					(thickness 0.15)
				)
				(justify left bottom)
				(hide yes)
			)
		)
		(property "Datasheet" "https://www.bourns.com/docs/product-datasheets/cr.pdf"
			(at 292.1 134.62 0)
			(effects
				(font
					(size 1.27 1.27)
					(thickness 0.15)
				)
				(justify left bottom)
				(hide yes)
			)
		)
		(property "Description" "SMD Chip Resistor, 330 ohm, ± 1%, 62.5 mW, 0402 [1005 Metric], Thick Film, General Purpose"
			(at 271.78 152.4 0)
			(effects
				(font
					(size 1.27 1.27)
				)
				(hide yes)
			)
		)
		(property "Manufacturer" "Bourns"
			(at 292.1 129.54 0)
			(effects
				(font
					(size 1.27 1.27)
					(thickness 0.15)
				)
				(justify left bottom)
				(hide yes)
			)
		)
		(property "MPN" "CR0402-FX-3300GLF"
			(at 292.1 132.08 0)
			(effects
				(font
					(size 1.27 1.27)
					(thickness 0.15)
				)
				(justify left bottom)
				(hide yes)
			)
		)
		(property "Val" "330R"
			(at 274.32 154.94 0)
			(effects
				(font
					(size 1.27 1.27)
					(thickness 0.15)
				)
			)
		)
		(property "License" "Apache-2.0"
			(at 292.1 127 0)
			(effects
				(font
					(size 1.27 1.27)
					(thickness 0.15)
				)
				(justify left bottom)
				(hide yes)
			)
		)
		(property "Author" "Antmicro"
			(at 292.1 124.46 0)
			(effects
				(font
					(size 1.27 1.27)
					(thickness 0.15)
				)
				(justify left bottom)
				(hide yes)
			)
		)
		(property "Tolerance" "1%"
			(at 292.1 142.24 0)
			(effects
				(font
					(size 1.27 1.27)
				)
				(justify left bottom)
				(hide yes)
			)
		)
		(pin "1"
		)
		(pin "2"
		)
		(instances
			(project "artix-dc-scm"
				(path ""
					(reference "R18")
					(unit 1)
				)
			)
		)
	)
	(symbol
		(lib_id "antmicroCapacitors0402:C_10u_0402")
		(at 246.38 104.14 90)
		(unit 1)
		(exclude_from_sim no)
		(in_bom yes)
		(on_board yes)
		(dnp no)
		(property "Reference" "C31"
			(at 247.015 99.695 90)
			(effects
				(font
					(size 1.27 1.27)
				)
				(justify right)
			)
		)
		(property "Value" "C_10u_0402"
			(at 256.54 83.82 0)
			(effects
				(font
					(size 1.27 1.27)
					(thickness 0.15)
				)
				(justify left bottom)
				(hide yes)
			)
		)
		(property "Footprint" "antmicro-footprints:C_0402_1005Metric"
			(at 259.08 83.82 0)
			(effects
				(font
					(size 1.27 1.27)
					(thickness 0.15)
				)
				(justify left bottom)
				(hide yes)
			)
		)
		(property "Datasheet" "https://www.yageo.com/en/Chart/Download/pdf/CC0402MRX5R5BB106"
			(at 261.62 83.82 0)
			(effects
				(font
					(size 1.27 1.27)
					(thickness 0.15)
				)
				(justify left bottom)
				(hide yes)
			)
		)
		(property "Description" "SMD Multilayer Ceramic Capacitor, 10 µF, 6.3 V, 0402 [1005 Metric], ± 20%, X5R, CC Series"
			(at 246.38 104.14 0)
			(effects
				(font
					(size 1.27 1.27)
				)
				(hide yes)
			)
		)
		(property "Manufacturer" "YAGEO"
			(at 266.7 83.82 0)
			(effects
				(font
					(size 1.27 1.27)
					(thickness 0.15)
				)
				(justify left bottom)
				(hide yes)
			)
		)
		(property "MPN" "CC0402MRX5R5BB106"
			(at 264.16 83.82 0)
			(effects
				(font
					(size 1.27 1.27)
					(thickness 0.15)
				)
				(justify left bottom)
				(hide yes)
			)
		)
		(property "Val" "10u"
			(at 247.015 103.505 90)
			(effects
				(font
					(size 1.27 1.27)
					(thickness 0.15)
				)
				(justify right)
			)
		)
		(property "License" "Apache-2.0"
			(at 269.24 83.82 0)
			(effects
				(font
					(size 1.27 1.27)
					(thickness 0.15)
				)
				(justify left bottom)
				(hide yes)
			)
		)
		(property "Author" "Antmicro"
			(at 271.78 83.82 0)
			(effects
				(font
					(size 1.27 1.27)
					(thickness 0.15)
				)
				(justify left bottom)
				(hide yes)
			)
		)
		(property "Voltage" ""
			(at 274.32 83.82 0)
			(effects
				(font
					(size 1.27 1.27)
				)
				(justify left bottom)
				(hide yes)
			)
		)
		(property "Dielectric" ""
			(at 276.86 83.82 0)
			(effects
				(font
					(size 1.27 1.27)
				)
				(justify left bottom)
				(hide yes)
			)
		)
		(pin "1"
		)
		(pin "2"
		)
		(instances
			(project "artix-dc-scm"
				(path ""
					(reference "C31")
					(unit 1)
				)
			)
		)
	)
	(symbol
		(lib_id "antmicroCapacitors0402:C_10u_0402")
		(at 254 104.14 90)
		(unit 1)
		(exclude_from_sim no)
		(in_bom yes)
		(on_board yes)
		(dnp no)
		(property "Reference" "C32"
			(at 254.635 99.695 90)
			(effects
				(font
					(size 1.27 1.27)
				)
				(justify right)
			)
		)
		(property "Value" "C_10u_0402"
			(at 264.16 83.82 0)
			(effects
				(font
					(size 1.27 1.27)
					(thickness 0.15)
				)
				(justify left bottom)
				(hide yes)
			)
		)
		(property "Footprint" "antmicro-footprints:C_0402_1005Metric"
			(at 266.7 83.82 0)
			(effects
				(font
					(size 1.27 1.27)
					(thickness 0.15)
				)
				(justify left bottom)
				(hide yes)
			)
		)
		(property "Datasheet" "https://www.yageo.com/en/Chart/Download/pdf/CC0402MRX5R5BB106"
			(at 269.24 83.82 0)
			(effects
				(font
					(size 1.27 1.27)
					(thickness 0.15)
				)
				(justify left bottom)
				(hide yes)
			)
		)
		(property "Description" "SMD Multilayer Ceramic Capacitor, 10 µF, 6.3 V, 0402 [1005 Metric], ± 20%, X5R, CC Series"
			(at 254 104.14 0)
			(effects
				(font
					(size 1.27 1.27)
				)
				(hide yes)
			)
		)
		(property "Manufacturer" "YAGEO"
			(at 274.32 83.82 0)
			(effects
				(font
					(size 1.27 1.27)
					(thickness 0.15)
				)
				(justify left bottom)
				(hide yes)
			)
		)
		(property "MPN" "CC0402MRX5R5BB106"
			(at 271.78 83.82 0)
			(effects
				(font
					(size 1.27 1.27)
					(thickness 0.15)
				)
				(justify left bottom)
				(hide yes)
			)
		)
		(property "Val" "10u"
			(at 254.635 103.505 90)
			(effects
				(font
					(size 1.27 1.27)
					(thickness 0.15)
				)
				(justify right)
			)
		)
		(property "License" "Apache-2.0"
			(at 276.86 83.82 0)
			(effects
				(font
					(size 1.27 1.27)
					(thickness 0.15)
				)
				(justify left bottom)
				(hide yes)
			)
		)
		(property "Author" "Antmicro"
			(at 279.4 83.82 0)
			(effects
				(font
					(size 1.27 1.27)
					(thickness 0.15)
				)
				(justify left bottom)
				(hide yes)
			)
		)
		(property "Voltage" ""
			(at 281.94 83.82 0)
			(effects
				(font
					(size 1.27 1.27)
				)
				(justify left bottom)
				(hide yes)
			)
		)
		(property "Dielectric" ""
			(at 284.48 83.82 0)
			(effects
				(font
					(size 1.27 1.27)
				)
				(justify left bottom)
				(hide yes)
			)
		)
		(pin "1"
		)
		(pin "2"
		)
		(instances
			(project "artix-dc-scm"
				(path ""
					(reference "C32")
					(unit 1)
				)
			)
		)
	)
	(symbol
		(lib_id "antmicroCapacitors0402:C_10u_0402")
		(at 261.62 104.14 90)
		(unit 1)
		(exclude_from_sim no)
		(in_bom yes)
		(on_board yes)
		(dnp no)
		(property "Reference" "C33"
			(at 262.255 99.695 90)
			(effects
				(font
					(size 1.27 1.27)
				)
				(justify right)
			)
		)
		(property "Value" "C_10u_0402"
			(at 271.78 83.82 0)
			(effects
				(font
					(size 1.27 1.27)
					(thickness 0.15)
				)
				(justify left bottom)
				(hide yes)
			)
		)
		(property "Footprint" "antmicro-footprints:C_0402_1005Metric"
			(at 274.32 83.82 0)
			(effects
				(font
					(size 1.27 1.27)
					(thickness 0.15)
				)
				(justify left bottom)
				(hide yes)
			)
		)
		(property "Datasheet" "https://www.yageo.com/en/Chart/Download/pdf/CC0402MRX5R5BB106"
			(at 276.86 83.82 0)
			(effects
				(font
					(size 1.27 1.27)
					(thickness 0.15)
				)
				(justify left bottom)
				(hide yes)
			)
		)
		(property "Description" "SMD Multilayer Ceramic Capacitor, 10 µF, 6.3 V, 0402 [1005 Metric], ± 20%, X5R, CC Series"
			(at 261.62 104.14 0)
			(effects
				(font
					(size 1.27 1.27)
				)
				(hide yes)
			)
		)
		(property "Manufacturer" "YAGEO"
			(at 281.94 83.82 0)
			(effects
				(font
					(size 1.27 1.27)
					(thickness 0.15)
				)
				(justify left bottom)
				(hide yes)
			)
		)
		(property "MPN" "CC0402MRX5R5BB106"
			(at 279.4 83.82 0)
			(effects
				(font
					(size 1.27 1.27)
					(thickness 0.15)
				)
				(justify left bottom)
				(hide yes)
			)
		)
		(property "Val" "10u"
			(at 262.255 103.505 90)
			(effects
				(font
					(size 1.27 1.27)
					(thickness 0.15)
				)
				(justify right)
			)
		)
		(property "License" "Apache-2.0"
			(at 284.48 83.82 0)
			(effects
				(font
					(size 1.27 1.27)
					(thickness 0.15)
				)
				(justify left bottom)
				(hide yes)
			)
		)
		(property "Author" "Antmicro"
			(at 287.02 83.82 0)
			(effects
				(font
					(size 1.27 1.27)
					(thickness 0.15)
				)
				(justify left bottom)
				(hide yes)
			)
		)
		(property "Voltage" ""
			(at 289.56 83.82 0)
			(effects
				(font
					(size 1.27 1.27)
				)
				(justify left bottom)
				(hide yes)
			)
		)
		(property "Dielectric" ""
			(at 292.1 83.82 0)
			(effects
				(font
					(size 1.27 1.27)
				)
				(justify left bottom)
				(hide yes)
			)
		)
		(pin "1"
		)
		(pin "2"
		)
		(instances
			(project "artix-dc-scm"
				(path ""
					(reference "C33")
					(unit 1)
				)
			)
		)
	)
	(symbol
		(lib_id "antmicroCapacitors0402:C_10u_0402")
		(at 269.24 104.14 90)
		(unit 1)
		(exclude_from_sim no)
		(in_bom yes)
		(on_board yes)
		(dnp no)
		(property "Reference" "C34"
			(at 269.875 99.695 90)
			(effects
				(font
					(size 1.27 1.27)
				)
				(justify right)
			)
		)
		(property "Value" "C_10u_0402"
			(at 279.4 83.82 0)
			(effects
				(font
					(size 1.27 1.27)
					(thickness 0.15)
				)
				(justify left bottom)
				(hide yes)
			)
		)
		(property "Footprint" "antmicro-footprints:C_0402_1005Metric"
			(at 281.94 83.82 0)
			(effects
				(font
					(size 1.27 1.27)
					(thickness 0.15)
				)
				(justify left bottom)
				(hide yes)
			)
		)
		(property "Datasheet" "https://www.yageo.com/en/Chart/Download/pdf/CC0402MRX5R5BB106"
			(at 284.48 83.82 0)
			(effects
				(font
					(size 1.27 1.27)
					(thickness 0.15)
				)
				(justify left bottom)
				(hide yes)
			)
		)
		(property "Description" "SMD Multilayer Ceramic Capacitor, 10 µF, 6.3 V, 0402 [1005 Metric], ± 20%, X5R, CC Series"
			(at 269.24 104.14 0)
			(effects
				(font
					(size 1.27 1.27)
				)
				(hide yes)
			)
		)
		(property "Manufacturer" "YAGEO"
			(at 289.56 83.82 0)
			(effects
				(font
					(size 1.27 1.27)
					(thickness 0.15)
				)
				(justify left bottom)
				(hide yes)
			)
		)
		(property "MPN" "CC0402MRX5R5BB106"
			(at 287.02 83.82 0)
			(effects
				(font
					(size 1.27 1.27)
					(thickness 0.15)
				)
				(justify left bottom)
				(hide yes)
			)
		)
		(property "Val" "10u"
			(at 269.875 103.505 90)
			(effects
				(font
					(size 1.27 1.27)
					(thickness 0.15)
				)
				(justify right)
			)
		)
		(property "License" "Apache-2.0"
			(at 292.1 83.82 0)
			(effects
				(font
					(size 1.27 1.27)
					(thickness 0.15)
				)
				(justify left bottom)
				(hide yes)
			)
		)
		(property "Author" "Antmicro"
			(at 294.64 83.82 0)
			(effects
				(font
					(size 1.27 1.27)
					(thickness 0.15)
				)
				(justify left bottom)
				(hide yes)
			)
		)
		(property "Voltage" ""
			(at 297.18 83.82 0)
			(effects
				(font
					(size 1.27 1.27)
				)
				(justify left bottom)
				(hide yes)
			)
		)
		(property "Dielectric" ""
			(at 299.72 83.82 0)
			(effects
				(font
					(size 1.27 1.27)
				)
				(justify left bottom)
				(hide yes)
			)
		)
		(pin "1"
		)
		(pin "2"
		)
		(instances
			(project "artix-dc-scm"
				(path ""
					(reference "C34")
					(unit 1)
				)
			)
		)
	)
	(symbol
		(lib_id "antmicroCapacitorsmisc:C_100n_6V3_0402")
		(at 186.69 149.86 180)
		(unit 1)
		(exclude_from_sim no)
		(in_bom yes)
		(on_board yes)
		(dnp no)
		(property "Reference" "C179"
			(at 178.435 148.59 0)
			(effects
				(font
					(size 1.27 1.27)
				)
			)
		)
		(property "Value" "C_100n_6V3_0402"
			(at 166.37 139.7 0)
			(effects
				(font
					(size 1.27 1.27)
					(thickness 0.15)
				)
				(justify left bottom)
				(hide yes)
			)
		)
		(property "Footprint" "antmicro-footprints:C_0402_1005Metric"
			(at 166.37 137.16 0)
			(effects
				(font
					(size 1.27 1.27)
					(thickness 0.15)
				)
				(justify left bottom)
				(hide yes)
			)
		)
		(property "Datasheet" "https://www.passivecomponent.com/wp-content/uploads/datasheet/WTC_MLCC_General_Purpose.pdf"
			(at 166.37 134.62 0)
			(effects
				(font
					(size 1.27 1.27)
					(thickness 0.15)
				)
				(justify left bottom)
				(hide yes)
			)
		)
		(property "Description" "SMT Multilayer Ceramic Capacitor, 0.1 µF, 6.3 V, 0402 [1005 Metric], ± 10%, X5R, Walsin MLCC"
			(at 186.69 149.86 0)
			(effects
				(font
					(size 1.27 1.27)
				)
				(hide yes)
			)
		)
		(property "Manufacturer" "Walsin"
			(at 166.37 129.54 0)
			(effects
				(font
					(size 1.27 1.27)
					(thickness 0.15)
				)
				(justify left bottom)
				(hide yes)
			)
		)
		(property "MPN" "0402X104K6R3CT"
			(at 166.37 132.08 0)
			(effects
				(font
					(size 1.27 1.27)
					(thickness 0.15)
				)
				(justify left bottom)
				(hide yes)
			)
		)
		(property "Val" "100n"
			(at 188.595 148.59 0)
			(effects
				(font
					(size 1.27 1.27)
					(thickness 0.15)
				)
			)
		)
		(property "License" "Apache-2.0"
			(at 166.37 127 0)
			(effects
				(font
					(size 1.27 1.27)
					(thickness 0.15)
				)
				(justify left bottom)
				(hide yes)
			)
		)
		(property "Author" "Antmicro"
			(at 166.37 124.46 0)
			(effects
				(font
					(size 1.27 1.27)
					(thickness 0.15)
				)
				(justify left bottom)
				(hide yes)
			)
		)
		(property "Voltage" ""
			(at 166.37 121.92 0)
			(effects
				(font
					(size 1.27 1.27)
				)
				(justify left bottom)
				(hide yes)
			)
		)
		(property "Dielectric" ""
			(at 166.37 119.38 0)
			(effects
				(font
					(size 1.27 1.27)
				)
				(justify left bottom)
				(hide yes)
			)
		)
		(property "Public" "False"
			(at 166.37 116.84 0)
			(effects
				(font
					(size 1.27 1.27)
				)
				(justify left bottom)
				(hide yes)
			)
		)
		(pin "1"
		)
		(pin "2"
		)
		(instances
			(project "artix-dc-scm"
				(path ""
					(reference "C179")
					(unit 1)
				)
			)
		)
	)
	(symbol
		(lib_id "antmicroCapacitorsmisc:C_100n_6V3_0402")
		(at 184.15 152.4 180)
		(unit 1)
		(exclude_from_sim no)
		(in_bom yes)
		(on_board yes)
		(dnp no)
		(property "Reference" "C181"
			(at 177.8 151.13 0)
			(effects
				(font
					(size 1.27 1.27)
				)
			)
		)
		(property "Value" "C_100n_6V3_0402"
			(at 163.83 142.24 0)
			(effects
				(font
					(size 1.27 1.27)
					(thickness 0.15)
				)
				(justify left bottom)
				(hide yes)
			)
		)
		(property "Footprint" "antmicro-footprints:C_0402_1005Metric"
			(at 163.83 139.7 0)
			(effects
				(font
					(size 1.27 1.27)
					(thickness 0.15)
				)
				(justify left bottom)
				(hide yes)
			)
		)
		(property "Datasheet" "https://www.passivecomponent.com/wp-content/uploads/datasheet/WTC_MLCC_General_Purpose.pdf"
			(at 163.83 137.16 0)
			(effects
				(font
					(size 1.27 1.27)
					(thickness 0.15)
				)
				(justify left bottom)
				(hide yes)
			)
		)
		(property "Description" "SMT Multilayer Ceramic Capacitor, 0.1 µF, 6.3 V, 0402 [1005 Metric], ± 10%, X5R, Walsin MLCC"
			(at 184.15 152.4 0)
			(effects
				(font
					(size 1.27 1.27)
				)
				(hide yes)
			)
		)
		(property "Manufacturer" "Walsin"
			(at 163.83 132.08 0)
			(effects
				(font
					(size 1.27 1.27)
					(thickness 0.15)
				)
				(justify left bottom)
				(hide yes)
			)
		)
		(property "MPN" "0402X104K6R3CT"
			(at 163.83 134.62 0)
			(effects
				(font
					(size 1.27 1.27)
					(thickness 0.15)
				)
				(justify left bottom)
				(hide yes)
			)
		)
		(property "Val" "100n"
			(at 187.96 151.13 0)
			(effects
				(font
					(size 1.27 1.27)
					(thickness 0.15)
				)
			)
		)
		(property "License" "Apache-2.0"
			(at 163.83 129.54 0)
			(effects
				(font
					(size 1.27 1.27)
					(thickness 0.15)
				)
				(justify left bottom)
				(hide yes)
			)
		)
		(property "Author" "Antmicro"
			(at 163.83 127 0)
			(effects
				(font
					(size 1.27 1.27)
					(thickness 0.15)
				)
				(justify left bottom)
				(hide yes)
			)
		)
		(property "Voltage" ""
			(at 163.83 124.46 0)
			(effects
				(font
					(size 1.27 1.27)
				)
				(justify left bottom)
				(hide yes)
			)
		)
		(property "Dielectric" ""
			(at 163.83 121.92 0)
			(effects
				(font
					(size 1.27 1.27)
				)
				(justify left bottom)
				(hide yes)
			)
		)
		(property "Public" "False"
			(at 163.83 119.38 0)
			(effects
				(font
					(size 1.27 1.27)
				)
				(justify left bottom)
				(hide yes)
			)
		)
		(pin "1"
		)
		(pin "2"
		)
		(instances
			(project "artix-dc-scm"
				(path ""
					(reference "C181")
					(unit 1)
				)
			)
		)
	)
	(symbol
		(lib_id "antmicroCapacitorsmisc:C_100n_6V3_0402")
		(at 186.69 165.1 180)
		(unit 1)
		(exclude_from_sim no)
		(in_bom yes)
		(on_board yes)
		(dnp no)
		(property "Reference" "C180"
			(at 178.435 163.83 0)
			(effects
				(font
					(size 1.27 1.27)
				)
			)
		)
		(property "Value" "C_100n_6V3_0402"
			(at 166.37 154.94 0)
			(effects
				(font
					(size 1.27 1.27)
					(thickness 0.15)
				)
				(justify left bottom)
				(hide yes)
			)
		)
		(property "Footprint" "antmicro-footprints:C_0402_1005Metric"
			(at 166.37 152.4 0)
			(effects
				(font
					(size 1.27 1.27)
					(thickness 0.15)
				)
				(justify left bottom)
				(hide yes)
			)
		)
		(property "Datasheet" "https://www.passivecomponent.com/wp-content/uploads/datasheet/WTC_MLCC_General_Purpose.pdf"
			(at 166.37 149.86 0)
			(effects
				(font
					(size 1.27 1.27)
					(thickness 0.15)
				)
				(justify left bottom)
				(hide yes)
			)
		)
		(property "Description" "SMT Multilayer Ceramic Capacitor, 0.1 µF, 6.3 V, 0402 [1005 Metric], ± 10%, X5R, Walsin MLCC"
			(at 186.69 165.1 0)
			(effects
				(font
					(size 1.27 1.27)
				)
				(hide yes)
			)
		)
		(property "Manufacturer" "Walsin"
			(at 166.37 144.78 0)
			(effects
				(font
					(size 1.27 1.27)
					(thickness 0.15)
				)
				(justify left bottom)
				(hide yes)
			)
		)
		(property "MPN" "0402X104K6R3CT"
			(at 166.37 147.32 0)
			(effects
				(font
					(size 1.27 1.27)
					(thickness 0.15)
				)
				(justify left bottom)
				(hide yes)
			)
		)
		(property "Val" "100n"
			(at 188.595 163.83 0)
			(effects
				(font
					(size 1.27 1.27)
					(thickness 0.15)
				)
			)
		)
		(property "License" "Apache-2.0"
			(at 166.37 142.24 0)
			(effects
				(font
					(size 1.27 1.27)
					(thickness 0.15)
				)
				(justify left bottom)
				(hide yes)
			)
		)
		(property "Author" "Antmicro"
			(at 166.37 139.7 0)
			(effects
				(font
					(size 1.27 1.27)
					(thickness 0.15)
				)
				(justify left bottom)
				(hide yes)
			)
		)
		(property "Voltage" ""
			(at 166.37 137.16 0)
			(effects
				(font
					(size 1.27 1.27)
				)
				(justify left bottom)
				(hide yes)
			)
		)
		(property "Dielectric" ""
			(at 166.37 134.62 0)
			(effects
				(font
					(size 1.27 1.27)
				)
				(justify left bottom)
				(hide yes)
			)
		)
		(property "Public" "False"
			(at 166.37 132.08 0)
			(effects
				(font
					(size 1.27 1.27)
				)
				(justify left bottom)
				(hide yes)
			)
		)
		(pin "1"
		)
		(pin "2"
		)
		(instances
			(project "artix-dc-scm"
				(path ""
					(reference "C180")
					(unit 1)
				)
			)
		)
	)
	(symbol
		(lib_id "antmicroCapacitorsmisc:C_100n_6V3_0402")
		(at 184.15 167.64 180)
		(unit 1)
		(exclude_from_sim no)
		(in_bom yes)
		(on_board yes)
		(dnp no)
		(property "Reference" "C182"
			(at 177.8 166.37 0)
			(effects
				(font
					(size 1.27 1.27)
				)
			)
		)
		(property "Value" "C_100n_6V3_0402"
			(at 163.83 157.48 0)
			(effects
				(font
					(size 1.27 1.27)
					(thickness 0.15)
				)
				(justify left bottom)
				(hide yes)
			)
		)
		(property "Footprint" "antmicro-footprints:C_0402_1005Metric"
			(at 163.83 154.94 0)
			(effects
				(font
					(size 1.27 1.27)
					(thickness 0.15)
				)
				(justify left bottom)
				(hide yes)
			)
		)
		(property "Datasheet" "https://www.passivecomponent.com/wp-content/uploads/datasheet/WTC_MLCC_General_Purpose.pdf"
			(at 163.83 152.4 0)
			(effects
				(font
					(size 1.27 1.27)
					(thickness 0.15)
				)
				(justify left bottom)
				(hide yes)
			)
		)
		(property "Description" "SMT Multilayer Ceramic Capacitor, 0.1 µF, 6.3 V, 0402 [1005 Metric], ± 10%, X5R, Walsin MLCC"
			(at 184.15 167.64 0)
			(effects
				(font
					(size 1.27 1.27)
				)
				(hide yes)
			)
		)
		(property "Manufacturer" "Walsin"
			(at 163.83 147.32 0)
			(effects
				(font
					(size 1.27 1.27)
					(thickness 0.15)
				)
				(justify left bottom)
				(hide yes)
			)
		)
		(property "MPN" "0402X104K6R3CT"
			(at 163.83 149.86 0)
			(effects
				(font
					(size 1.27 1.27)
					(thickness 0.15)
				)
				(justify left bottom)
				(hide yes)
			)
		)
		(property "Val" "100n"
			(at 187.96 166.37 0)
			(effects
				(font
					(size 1.27 1.27)
					(thickness 0.15)
				)
			)
		)
		(property "License" "Apache-2.0"
			(at 163.83 144.78 0)
			(effects
				(font
					(size 1.27 1.27)
					(thickness 0.15)
				)
				(justify left bottom)
				(hide yes)
			)
		)
		(property "Author" "Antmicro"
			(at 163.83 142.24 0)
			(effects
				(font
					(size 1.27 1.27)
					(thickness 0.15)
				)
				(justify left bottom)
				(hide yes)
			)
		)
		(property "Voltage" ""
			(at 163.83 139.7 0)
			(effects
				(font
					(size 1.27 1.27)
				)
				(justify left bottom)
				(hide yes)
			)
		)
		(property "Dielectric" ""
			(at 163.83 137.16 0)
			(effects
				(font
					(size 1.27 1.27)
				)
				(justify left bottom)
				(hide yes)
			)
		)
		(property "Public" "False"
			(at 163.83 134.62 0)
			(effects
				(font
					(size 1.27 1.27)
				)
				(justify left bottom)
				(hide yes)
			)
		)
		(pin "1"
		)
		(pin "2"
		)
		(instances
			(project "artix-dc-scm"
				(path ""
					(reference "C182")
					(unit 1)
				)
			)
		)
	)
	(symbol
		(lib_id "antmicroTestPoints:TP_1mm_SMD")
		(at 175.26 102.87 180)
		(unit 1)
		(exclude_from_sim no)
		(in_bom no)
		(on_board yes)
		(dnp no)
		(property "Reference" "TP12"
			(at 168.275 102.87 0)
			(effects
				(font
					(size 1.27 1.27)
				)
			)
		)
		(property "Value" "TP_1mm_SMD"
			(at 175.26 100.33 0)
			(effects
				(font
					(size 1.27 1.27)
				)
				(hide yes)
			)
		)
		(property "Footprint" "antmicro-footprints:TP_SMD_1mm"
			(at 160.02 92.71 0)
			(effects
				(font
					(size 1.27 1.27)
					(thickness 0.15)
				)
				(justify left bottom)
				(hide yes)
			)
		)
		(property "Datasheet" ""
			(at 160.02 90.17 0)
			(effects
				(font
					(size 1.27 1.27)
					(thickness 0.15)
				)
				(justify left bottom)
				(hide yes)
			)
		)
		(property "Description" "Test point 1mm SMD"
			(at 175.26 102.87 0)
			(effects
				(font
					(size 1.27 1.27)
				)
				(hide yes)
			)
		)
		(property "MPN" ""
			(at 175.26 102.87 0)
			(effects
				(font
					(size 1.27 1.27)
				)
				(hide yes)
			)
		)
		(property "Manufacturer" ""
			(at 175.26 102.87 0)
			(effects
				(font
					(size 1.27 1.27)
				)
				(hide yes)
			)
		)
		(property "Author" "Antmicro"
			(at 160.02 87.63 0)
			(effects
				(font
					(size 1.27 1.27)
					(thickness 0.15)
				)
				(justify left bottom)
				(hide yes)
			)
		)
		(property "License" "Apache-2.0"
			(at 160.02 85.09 0)
			(effects
				(font
					(size 1.27 1.27)
					(thickness 0.15)
				)
				(justify left bottom)
				(hide yes)
			)
		)
		(pin "1"
		)
		(instances
			(project "artix-dc-scm"
				(path ""
					(reference "TP12")
					(unit 1)
				)
			)
		)
	)
	(symbol
		(lib_id "antmicroTestPoints:TP_1mm_SMD")
		(at 175.26 100.33 180)
		(unit 1)
		(exclude_from_sim no)
		(in_bom no)
		(on_board yes)
		(dnp no)
		(property "Reference" "TP13"
			(at 168.275 100.33 0)
			(effects
				(font
					(size 1.27 1.27)
				)
			)
		)
		(property "Value" "TP_1mm_SMD"
			(at 175.26 97.79 0)
			(effects
				(font
					(size 1.27 1.27)
				)
				(hide yes)
			)
		)
		(property "Footprint" "antmicro-footprints:TP_SMD_1mm"
			(at 160.02 90.17 0)
			(effects
				(font
					(size 1.27 1.27)
					(thickness 0.15)
				)
				(justify left bottom)
				(hide yes)
			)
		)
		(property "Datasheet" ""
			(at 160.02 87.63 0)
			(effects
				(font
					(size 1.27 1.27)
					(thickness 0.15)
				)
				(justify left bottom)
				(hide yes)
			)
		)
		(property "Description" "Test point 1mm SMD"
			(at 175.26 100.33 0)
			(effects
				(font
					(size 1.27 1.27)
				)
				(hide yes)
			)
		)
		(property "MPN" ""
			(at 175.26 100.33 0)
			(effects
				(font
					(size 1.27 1.27)
				)
				(hide yes)
			)
		)
		(property "Manufacturer" ""
			(at 175.26 100.33 0)
			(effects
				(font
					(size 1.27 1.27)
				)
				(hide yes)
			)
		)
		(property "Author" "Antmicro"
			(at 160.02 85.09 0)
			(effects
				(font
					(size 1.27 1.27)
					(thickness 0.15)
				)
				(justify left bottom)
				(hide yes)
			)
		)
		(property "License" "Apache-2.0"
			(at 160.02 82.55 0)
			(effects
				(font
					(size 1.27 1.27)
					(thickness 0.15)
				)
				(justify left bottom)
				(hide yes)
			)
		)
		(pin "1"
		)
		(instances
			(project "artix-dc-scm"
				(path ""
					(reference "TP13")
					(unit 1)
				)
			)
		)
	)
	(symbol
		(lib_id "antmicroTestPoints:TP_1mm_SMD")
		(at 175.26 97.79 0)
		(mirror y)
		(unit 1)
		(exclude_from_sim no)
		(in_bom no)
		(on_board yes)
		(dnp no)
		(property "Reference" "TP14"
			(at 168.275 97.79 0)
			(effects
				(font
					(size 1.27 1.27)
				)
			)
		)
		(property "Value" "TP_1mm_SMD"
			(at 175.26 100.33 0)
			(effects
				(font
					(size 1.27 1.27)
				)
				(hide yes)
			)
		)
		(property "Footprint" "antmicro-footprints:TP_SMD_1mm"
			(at 160.02 107.95 0)
			(effects
				(font
					(size 1.27 1.27)
					(thickness 0.15)
				)
				(justify left bottom)
				(hide yes)
			)
		)
		(property "Datasheet" ""
			(at 160.02 110.49 0)
			(effects
				(font
					(size 1.27 1.27)
					(thickness 0.15)
				)
				(justify left bottom)
				(hide yes)
			)
		)
		(property "Description" "Test point 1mm SMD"
			(at 175.26 97.79 0)
			(effects
				(font
					(size 1.27 1.27)
				)
				(hide yes)
			)
		)
		(property "MPN" ""
			(at 175.26 97.79 0)
			(effects
				(font
					(size 1.27 1.27)
				)
				(hide yes)
			)
		)
		(property "Manufacturer" ""
			(at 175.26 97.79 0)
			(effects
				(font
					(size 1.27 1.27)
				)
				(hide yes)
			)
		)
		(property "Author" "Antmicro"
			(at 160.02 113.03 0)
			(effects
				(font
					(size 1.27 1.27)
					(thickness 0.15)
				)
				(justify left bottom)
				(hide yes)
			)
		)
		(property "License" "Apache-2.0"
			(at 160.02 115.57 0)
			(effects
				(font
					(size 1.27 1.27)
					(thickness 0.15)
				)
				(justify left bottom)
				(hide yes)
			)
		)
		(pin "1"
		)
		(instances
			(project "artix-dc-scm"
				(path ""
					(reference "TP14")
					(unit 1)
				)
			)
		)
	)
	(symbol
		(lib_id "antmicroLEDIndicationDiscrete:LED_G_0603_KP-1608CGCK")
		(at 257.81 152.4 0)
		(unit 1)
		(exclude_from_sim no)
		(in_bom yes)
		(on_board yes)
		(dnp no)
		(fields_autoplaced yes)
		(property "Reference" "D1"
			(at 260.35 142.24 0)
			(effects
				(font
					(size 1.27 1.27)
				)
			)
		)
		(property "Value" "LED_G_0603_KP-1608CGCK"
			(at 280.67 160.02 0)
			(effects
				(font
					(size 1.27 1.27)
					(thickness 0.15)
				)
				(justify left bottom)
				(hide yes)
			)
		)
		(property "Footprint" "antmicro-footprints:LED_0603_1608Metric_G"
			(at 280.67 162.56 0)
			(effects
				(font
					(size 1.27 1.27)
					(thickness 0.15)
				)
				(justify left bottom)
				(hide yes)
			)
		)
		(property "Datasheet" "http://www.kingbright.com/attachments/file/psearch//000/00/00/KP-1608CGCK(Ver.23B).pdf"
			(at 280.67 165.1 0)
			(effects
				(font
					(size 1.27 1.27)
					(thickness 0.15)
				)
				(justify left bottom)
				(hide yes)
			)
		)
		(property "Description" "LED, Green, SMD, 0603, 20 mA, 2.1 V, 570 nm"
			(at 257.81 152.4 0)
			(effects
				(font
					(size 1.27 1.27)
				)
				(hide yes)
			)
		)
		(property "MPN" "KP-1608CGCK"
			(at 260.35 144.78 0)
			(effects
				(font
					(size 1.27 1.27)
					(thickness 0.15)
				)
			)
		)
		(property "Manufacturer" "Kingbright"
			(at 280.67 170.18 0)
			(effects
				(font
					(size 1.27 1.27)
					(thickness 0.15)
				)
				(justify left bottom)
				(hide yes)
			)
		)
		(property "Author" "Antmicro"
			(at 280.67 172.72 0)
			(effects
				(font
					(size 1.27 1.27)
					(thickness 0.15)
				)
				(justify left bottom)
				(hide yes)
			)
		)
		(property "License" "Apache-2.0"
			(at 280.67 175.26 0)
			(effects
				(font
					(size 1.27 1.27)
					(thickness 0.15)
				)
				(justify left bottom)
				(hide yes)
			)
		)
		(property "Color" "Green"
			(at 260.35 147.32 0)
			(effects
				(font
					(size 1.27 1.27)
				)
			)
		)
		(pin "1"
		)
		(pin "2"
		)
		(instances
			(project "artix-dc-scm"
				(path ""
					(reference "D1")
					(unit 1)
				)
			)
		)
	)
	(symbol
		(lib_id "antmicropower:GND")
		(at 246.38 176.53 0)
		(unit 1)
		(exclude_from_sim no)
		(in_bom yes)
		(on_board yes)
		(dnp no)
		(property "Reference" "#PWR0212"
			(at 246.38 182.88 0)
			(effects
				(font
					(size 1.27 1.27)
				)
				(hide yes)
			)
		)
		(property "Value" "GND"
			(at 246.38 180.34 0)
			(effects
				(font
					(size 1.27 1.27)
				)
			)
		)
		(property "Footprint" ""
			(at 246.38 176.53 0)
			(effects
				(font
					(size 1.27 1.27)
				)
				(hide yes)
			)
		)
		(property "Datasheet" ""
			(at 246.38 176.53 0)
			(effects
				(font
					(size 1.27 1.27)
				)
				(hide yes)
			)
		)
		(property "Description" ""
			(at 246.38 176.53 0)
			(effects
				(font
					(size 1.27 1.27)
				)
				(hide yes)
			)
		)
		(property "Author" "Antmicro"
			(at 255.27 184.15 0)
			(effects
				(font
					(size 1.27 1.27)
					(thickness 0.15)
				)
				(justify left bottom)
				(hide yes)
			)
		)
		(property "License" "Apache-2.0"
			(at 255.27 186.69 0)
			(effects
				(font
					(size 1.27 1.27)
					(thickness 0.15)
				)
				(justify left bottom)
				(hide yes)
			)
		)
		(pin "1"
		)
		(instances
			(project "artix-dc-scm"
				(path ""
					(reference "#PWR0212")
					(unit 1)
				)
			)
		)
	)
	(symbol
		(lib_id "antmicroMechanicalParts:Spacer_Drill3.7mm_H2.5mm_9774025151R")
		(at 224.79 185.42 0)
		(unit 1)
		(exclude_from_sim no)
		(in_bom yes)
		(on_board yes)
		(dnp no)
		(fields_autoplaced yes)
		(property "Reference" "H1"
			(at 233.68 184.15 0)
			(effects
				(font
					(size 1.27 1.27)
					(thickness 0.15)
				)
				(justify left)
			)
		)
		(property "Value" "Spacer_Drill3.7mm_H2.5mm_9774025151R"
			(at 233.68 186.69 0)
			(effects
				(font
					(size 1.27 1.27)
					(thickness 0.15)
				)
				(justify left)
			)
		)
		(property "Footprint" "antmicro-footprints:Spacer_Drill3.7mm_H2.5mm_9774025151R"
			(at 247.65 193.04 0)
			(effects
				(font
					(size 1.27 1.27)
					(thickness 0.15)
				)
				(justify left bottom)
				(hide yes)
			)
		)
		(property "Datasheet" "https://www.we-online.com/components/products/datasheet/9774025151R.pdf"
			(at 247.65 195.58 0)
			(effects
				(font
					(size 1.27 1.27)
					(thickness 0.15)
				)
				(justify left bottom)
				(hide yes)
			)
		)
		(property "Description" "Spacer, SMT, Non Stop, Steel, Swage Round, 5.1 mm x 2.5 mm, M2.5 Thread, WA-SMSI Series"
			(at 224.79 185.42 0)
			(effects
				(font
					(size 1.27 1.27)
				)
				(hide yes)
			)
		)
		(property "Manufacturer" "Würth Elektronik"
			(at 247.65 198.12 0)
			(effects
				(font
					(size 1.27 1.27)
					(thickness 0.15)
				)
				(justify left bottom)
				(hide yes)
			)
		)
		(property "MPN" "9774025151R"
			(at 247.65 200.66 0)
			(effects
				(font
					(size 1.27 1.27)
					(thickness 0.15)
				)
				(justify left bottom)
				(hide yes)
			)
		)
		(property "Author" "Antmicro"
			(at 247.65 203.2 0)
			(effects
				(font
					(size 1.27 1.27)
					(thickness 0.15)
				)
				(justify left bottom)
				(hide yes)
			)
		)
		(property "License" "Apache-2.0"
			(at 247.65 205.74 0)
			(effects
				(font
					(size 1.27 1.27)
					(thickness 0.15)
				)
				(justify left bottom)
				(hide yes)
			)
		)
		(pin "1"
		)
		(instances
			(project "artix-dc-scm"
				(path ""
					(reference "H1")
					(unit 1)
				)
			)
		)
	)
	(symbol
		(lib_id "antmicropower:GND")
		(at 269.24 106.68 0)
		(unit 1)
		(exclude_from_sim no)
		(in_bom yes)
		(on_board yes)
		(dnp no)
		(property "Reference" "#PWR0213"
			(at 269.24 113.03 0)
			(effects
				(font
					(size 1.27 1.27)
				)
				(hide yes)
			)
		)
		(property "Value" "GND"
			(at 269.24 110.49 0)
			(effects
				(font
					(size 1.27 1.27)
				)
			)
		)
		(property "Footprint" ""
			(at 269.24 106.68 0)
			(effects
				(font
					(size 1.27 1.27)
				)
				(hide yes)
			)
		)
		(property "Datasheet" ""
			(at 269.24 106.68 0)
			(effects
				(font
					(size 1.27 1.27)
				)
				(hide yes)
			)
		)
		(property "Description" ""
			(at 269.24 106.68 0)
			(effects
				(font
					(size 1.27 1.27)
				)
				(hide yes)
			)
		)
		(property "Author" "Antmicro"
			(at 278.13 114.3 0)
			(effects
				(font
					(size 1.27 1.27)
					(thickness 0.15)
				)
				(justify left bottom)
				(hide yes)
			)
		)
		(property "License" "Apache-2.0"
			(at 278.13 116.84 0)
			(effects
				(font
					(size 1.27 1.27)
					(thickness 0.15)
				)
				(justify left bottom)
				(hide yes)
			)
		)
		(pin "1"
		)
		(instances
			(project "artix-dc-scm"
				(path ""
					(reference "#PWR0213")
					(unit 1)
				)
			)
		)
	)
)
